# T6G (Grand Teton) — schematic netlist excerpt (pin names and nets, part order shuffled) for the footprints in the layout excerpt that follows; sources: Cadence DE-HDL packaged netlist, KiCad conversion of 04192023_DAF0TMB3IC0_F0TG_MB_C_brd_V02_OCP.brd

PR266  Q_RES  5.6 1% CHIP  pkg 0402LF  page 219 : A = SW_PVDDCR_CPU1_P1_BOOT4 ; B = SW_PVDDCR_CPU1_P1_BOOT4_R
R969  Q_RES  1K 1% CHIP  pkg 0201LF  page 276 : A = RT_CPU0_P0_ADDR1 ; B = GND
PR274  Q_RES  8.87K 1% EMPTY  pkg 0402LF  page 222 : A = PVDDIO_P1_LSET2 ; B = GND

(kicad_pcb
	(version 20260206)
	(generator "pcbnew")
	(generator_version "10.0")
	(general
		(thickness 1.6)
		(legacy_teardrops no)
	)
	(paper "A4")
	(title_block
		(title "04192023_DAF0TMB3IC0_F0TG_MB_C_brd_V02_OCP.brd")
		(comment 1 "Grand Teton / footprints 4035-4037 of 8354")
	)
	(layers
		(0 "F.Cu" signal "TOP")
		(4 "In1.Cu" signal "GND")
		(6 "In2.Cu" signal "IN1")
		(8 "In3.Cu" signal "GND1")
		(10 "In4.Cu" signal "IN2")
		(12 "In5.Cu" signal "GND2")
		(14 "In6.Cu" signal "IN3")
		(16 "In7.Cu" signal "GND3")
		(18 "In8.Cu" signal "VCC")
		(20 "In9.Cu" signal "VCC1")
		(22 "In10.Cu" signal "GND4")
		(24 "In11.Cu" signal "IN4")
		(26 "In12.Cu" signal "GND5")
		(28 "In13.Cu" signal "IN5")
		(30 "In14.Cu" signal "GND6")
		(32 "In15.Cu" signal "IN6")
		(34 "In16.Cu" signal "GND7")
		(2 "B.Cu" signal "BOTTOM")
		(9 "F.Adhes" user "F.Adhesive")
		(11 "B.Adhes" user "B.Adhesive")
		(13 "F.Paste" user "Package Geometry/Pastemask Top")
		(15 "B.Paste" user "Package Geometry/Pastemask Bottom")
		(5 "F.SilkS" user "Ref Des/Silkscreen Top")
		(7 "B.SilkS" user "Ref Des/Silkscreen Bottom")
		(1 "F.Mask" user "Board Geometry/Soldermask Top")
		(3 "B.Mask" user "Board Geometry/Soldermask Bottom")
		(17 "Dwgs.User" user "User.Drawings")
		(19 "Cmts.User" user "User.Comments")
		(21 "Eco1.User" user "User.Eco1")
		(23 "Eco2.User" user "User.Eco2")
		(25 "Edge.Cuts" user "Board Geometry/Outline")
		(27 "Margin" user)
		(31 "F.CrtYd" user "Package Geometry/Place Bound Top")
		(29 "B.CrtYd" user "Package Geometry/Place Bound Bottom")
		(35 "F.Fab" user "Ref Des/Assembly Top")
		(33 "B.Fab" user "Ref Des/Assembly Bottom")
	)
	(footprint ""
		(layer "F.Cu")
		(at 328.288142 -390.652)
		(property "Reference" "R969"
			(at 0 0 0)
			(layer "F.SilkS")
			(hide yes)
			(effects
				(font
					(size 1.27 1.27)
				)
			)
		)
		(property "Value" ""
			(at 0 0 0)
			(layer "F.Fab")
			(effects
				(font
					(size 1.27 1.27)
				)
			)
		)
		(duplicate_pad_numbers_are_jumpers no)
		(fp_line
			(start -0.32512 -0.175006)
			(end 0.32512 -0.175006)
			(stroke
				(width 0.1)
				(type default)
			)
			(layer "F.Fab")
		)
		(fp_line
			(start -0.32512 0.175006)
			(end -0.32512 -0.175006)
			(stroke
				(width 0.1)
				(type default)
			)
			(layer "F.Fab")
		)
		(fp_line
			(start 0.32512 -0.175006)
			(end 0.32512 0.175006)
			(stroke
				(width 0.1)
				(type default)
			)
			(layer "F.Fab")
		)
		(fp_line
			(start 0.32512 0.175006)
			(end -0.32512 0.175006)
			(stroke
				(width 0.1)
				(type default)
			)
			(layer "F.Fab")
		)
		(pad "1" smd rect
			(at -0.2667 0)
			(size 0.3048 0.381)
			(layers "F.Cu" "F.Mask" "F.Paste")
			(net "RT_CPU0_P0_ADDR1")
		)
		(pad "2" smd rect
			(at 0.2667 0 180)
			(size 0.3048 0.381)
			(layers "F.Cu" "F.Mask" "F.Paste")
			(net "GND")
		)
	)
	(footprint ""
		(layer "F.Cu")
		(at 62.63386 -351.372932 90)
		(property "Reference" "PR266"
			(at 0 0 90)
			(layer "F.SilkS")
			(hide yes)
			(effects
				(font
					(size 1.27 1.27)
				)
			)
		)
		(property "Value" ""
			(at 0 0 90)
			(layer "F.Fab")
			(effects
				(font
					(size 1.27 1.27)
				)
			)
		)
		(duplicate_pad_numbers_are_jumpers no)
		(fp_line
			(start 0.7874 -0.4064)
			(end 0.7874 0.4064)
			(stroke
				(width 0.1524)
				(type default)
			)
			(layer "F.SilkS")
		)
		(fp_line
			(start -0.7874 -0.4064)
			(end 0.7874 -0.4064)
			(stroke
				(width 0.1524)
				(type default)
			)
			(layer "F.SilkS")
		)
		(fp_line
			(start 0.7874 0.4064)
			(end -0.7874 0.4064)
			(stroke
				(width 0.1524)
				(type default)
			)
			(layer "F.SilkS")
		)
		(fp_line
			(start -0.7874 0.4064)
			(end -0.7874 -0.4064)
			(stroke
				(width 0.1524)
				(type default)
			)
			(layer "F.SilkS")
		)
		(fp_line
			(start -0.12065 -0.305054)
			(end -0.12065 -0.2794)
			(stroke
				(width 0.1)
				(type default)
			)
			(layer "F.Fab")
		)
		(fp_line
			(start -0.67945 -0.305054)
			(end -0.12065 -0.305054)
			(stroke
				(width 0.1)
				(type default)
			)
			(layer "F.Fab")
		)
		(fp_line
			(start 0.67945 -0.3048)
			(end 0.67945 0.3048)
			(stroke
				(width 0.1)
				(type default)
			)
			(layer "F.Fab")
		)
		(fp_line
			(start 0.12065 -0.3048)
			(end 0.67945 -0.3048)
			(stroke
				(width 0.1)
				(type default)
			)
			(layer "F.Fab")
		)
		(fp_line
			(start 0.12065 -0.2794)
			(end 0.12065 -0.3048)
			(stroke
				(width 0.1)
				(type default)
			)
			(layer "F.Fab")
		)
		(fp_line
			(start -0.12065 -0.2794)
			(end 0.12065 -0.2794)
			(stroke
				(width 0.1)
				(type default)
			)
			(layer "F.Fab")
		)
		(fp_line
			(start 0.120396 0.2794)
			(end -0.12065 0.2794)
			(stroke
				(width 0.1)
				(type default)
			)
			(layer "F.Fab")
		)
		(fp_line
			(start -0.12065 0.2794)
			(end -0.12065 0.3048)
			(stroke
				(width 0.1)
				(type default)
			)
			(layer "F.Fab")
		)
		(fp_line
			(start 0.67945 0.3048)
			(end 0.120396 0.3048)
			(stroke
				(width 0.1)
				(type default)
			)
			(layer "F.Fab")
		)
		(fp_line
			(start 0.120396 0.3048)
			(end 0.120396 0.2794)
			(stroke
				(width 0.1)
				(type default)
			)
			(layer "F.Fab")
		)
		(fp_line
			(start -0.12065 0.3048)
			(end -0.67945 0.3048)
			(stroke
				(width 0.1)
				(type default)
			)
			(layer "F.Fab")
		)
		(fp_line
			(start -0.67945 0.3048)
			(end -0.67945 -0.305054)
			(stroke
				(width 0.1)
				(type default)
			)
			(layer "F.Fab")
		)
		(pad "1" smd circle
			(at -0.40005 0 90)
			(size 0 0)
			(layers "F.Cu" "F.Mask" "F.Paste")
			(net "SW_PVDDCR_CPU1_P1_BOOT4")
		)
		(pad "2" smd circle
			(at 0.40005 0 90)
			(size 0 0)
			(layers "F.Cu" "F.Mask" "F.Paste")
			(net "SW_PVDDCR_CPU1_P1_BOOT4_R")
		)
	)
	(footprint ""
		(layer "F.Cu")
		(at 43.88231 -351.932748)
		(property "Reference" "PR274"
			(at 0 0 0)
			(layer "F.SilkS")
			(hide yes)
			(effects
				(font
					(size 1.27 1.27)
				)
			)
		)
		(property "Value" ""
			(at 0 0 0)
			(layer "F.Fab")
			(effects
				(font
					(size 1.27 1.27)
				)
			)
		)
		(duplicate_pad_numbers_are_jumpers no)
		(fp_line
			(start -0.7874 -0.4064)
			(end 0.7874 -0.4064)
			(stroke
				(width 0.1524)
				(type default)
			)
			(layer "F.SilkS")
		)
		(fp_line
			(start -0.7874 0.4064)
			(end -0.7874 -0.4064)
			(stroke
				(width 0.1524)
				(type default)
			)
			(layer "F.SilkS")
		)
		(fp_line
			(start 0.7874 -0.4064)
			(end 0.7874 0.4064)
			(stroke
				(width 0.1524)
				(type default)
			)
			(layer "F.SilkS")
		)
		(fp_line
			(start 0.7874 0.4064)
			(end -0.7874 0.4064)
			(stroke
				(width 0.1524)
				(type default)
			)
			(layer "F.SilkS")
		)
		(fp_line
			(start -0.67945 -0.305054)
			(end -0.12065 -0.305054)
			(stroke
				(width 0.1)
				(type default)
			)
			(layer "F.Fab")
		)
		(fp_line
			(start -0.67945 0.3048)
			(end -0.67945 -0.305054)
			(stroke
				(width 0.1)
				(type default)
			)
			(layer "F.Fab")
		)
		(fp_line
			(start -0.12065 -0.305054)
			(end -0.12065 -0.2794)
			(stroke
				(width 0.1)
				(type default)
			)
			(layer "F.Fab")
		)
		(fp_line
			(start -0.12065 -0.2794)
			(end 0.12065 -0.2794)
			(stroke
				(width 0.1)
				(type default)
			)
			(layer "F.Fab")
		)
		(fp_line
			(start -0.12065 0.2794)
			(end -0.12065 0.3048)
			(stroke
				(width 0.1)
				(type default)
			)
			(layer "F.Fab")
		)
		(fp_line
			(start -0.12065 0.3048)
			(end -0.67945 0.3048)
			(stroke
				(width 0.1)
				(type default)
			)
			(layer "F.Fab")
		)
		(fp_line
			(start 0.120396 0.2794)
			(end -0.12065 0.2794)
			(stroke
				(width 0.1)
				(type default)
			)
			(layer "F.Fab")
		)
		(fp_line
			(start 0.120396 0.3048)
			(end 0.120396 0.2794)
			(stroke
				(width 0.1)
				(type default)
			)
			(layer "F.Fab")
		)
		(fp_line
			(start 0.12065 -0.3048)
			(end 0.67945 -0.3048)
			(stroke
				(width 0.1)
				(type default)
			)
			(layer "F.Fab")
		)
		(fp_line
			(start 0.12065 -0.2794)
			(end 0.12065 -0.3048)
			(stroke
				(width 0.1)
				(type default)
			)
			(layer "F.Fab")
		)
		(fp_line
			(start 0.67945 -0.3048)
			(end 0.67945 0.3048)
			(stroke
				(width 0.1)
				(type default)
			)
			(layer "F.Fab")
		)
		(fp_line
			(start 0.67945 0.3048)
			(end 0.120396 0.3048)
			(stroke
				(width 0.1)
				(type default)
			)
			(layer "F.Fab")
		)
		(pad "1" smd circle
			(at -0.40005 0)
			(size 0 0)
			(layers "F.Cu" "F.Mask" "F.Paste")
			(net "PVDDIO_P1_LSET2")
		)
		(pad "2" smd circle
			(at 0.40005 0)
			(size 0 0)
			(layers "F.Cu" "F.Mask" "F.Paste")
			(net "GND")
		)
	)
)
